(kicad_pcb
	(version 20241229)
	(generator "pcbnew")
	(generator_version "9.0")
	(general
		(thickness 1.6642)
		(legacy_teardrops no)
	)
	(paper "A3")
	(title_block
		(title "PolarFire SoM")
		(date "2025-07-22")
		(rev "1.1.4")
		(company "Antmicro Ltd")
		(comment 1 "www.antmicro.com")
		(comment 9 "footprints 297-300 of 470")
	)
	(layers
		(0 "F.Cu" mixed)
		(4 "In1.Cu" power)
		(6 "In2.Cu" signal)
		(8 "In3.Cu" power)
		(10 "In4.Cu" signal)
		(12 "In5.Cu" power)
		(14 "In6.Cu" power)
		(16 "In7.Cu" signal)
		(18 "In8.Cu" power)
		(20 "In9.Cu" signal)
		(22 "In10.Cu" power)
		(24 "In11.Cu" signal)
		(26 "In12.Cu" signal)
		(2 "B.Cu" mixed)
		(9 "F.Adhes" user "F.Adhesive")
		(11 "B.Adhes" user "B.Adhesive")
		(13 "F.Paste" user)
		(15 "B.Paste" user)
		(5 "F.SilkS" user "F.Silkscreen")
		(7 "B.SilkS" user "B.Silkscreen")
		(1 "F.Mask" user)
		(3 "B.Mask" user)
		(17 "Dwgs.User" user "User.Drawings")
		(19 "Cmts.User" user "User.Comments")
		(21 "Eco1.User" user "User.Eco1")
		(23 "Eco2.User" user "User.Eco2")
		(25 "Edge.Cuts" user)
		(27 "Margin" user)
		(31 "F.CrtYd" user "F.Courtyard")
		(29 "B.CrtYd" user "B.Courtyard")
		(35 "F.Fab" user)
		(33 "B.Fab" user)
	)
	(footprint "antmicro-footprints:C_0402_1005Metric"
		(layer "B.Cu")
		(at 197.299 127.19 -90)
		(descr "Capacitor SMD 0402")
		(tags "capacitor SMD 0402")
		(property "Reference" "C6"
			(at -1.14 -1.351 90)
			(layer "B.SilkS")
			(effects
				(font
					(size 0.7 0.7)
					(thickness 0.15)
				)
				(justify left bottom mirror)
			)
		)
		(property "Value" "C_100n_0402"
			(at -1.022927 -2.155213 90)
			(layer "B.Fab")
			(hide yes)
			(effects
				(font
					(size 0.7 0.7)
					(thickness 0.15)
				)
				(justify left bottom mirror)
			)
		)
		(property "Datasheet" "https://www.murata.com/products/productdetail?partno=GRM155R61H104KE14%23"
			(at 0 0 270)
			(layer "F.Fab")
			(hide yes)
			(effects
				(font
					(size 1.27 1.27)
					(thickness 0.15)
				)
			)
		)
		(property "Description" "SMD Multilayer Ceramic Capacitor, 0.1 µF, 50 V, 0402 [1005 Metric], ± 10%, X5R, GRM Series"
			(at 0 0 270)
			(layer "F.Fab")
			(hide yes)
			(effects
				(font
					(size 1.27 1.27)
					(thickness 0.15)
				)
			)
		)
		(property "Author" "Antmicro"
			(at 70.109 324.489 0)
			(layer "B.Fab")
			(hide yes)
			(effects
				(font
					(size 1 1)
					(thickness 0.15)
				)
				(justify mirror)
			)
		)
		(property "Dielectric" "X5R"
			(at 70.109 324.489 0)
			(layer "B.Fab")
			(hide yes)
			(effects
				(font
					(size 1 1)
					(thickness 0.15)
				)
				(justify mirror)
			)
		)
		(property "License" "Apache-2.0"
			(at 70.109 324.489 0)
			(layer "B.Fab")
			(hide yes)
			(effects
				(font
					(size 1 1)
					(thickness 0.15)
				)
				(justify mirror)
			)
		)
		(property "MPN" "GRM155R61H104KE14D"
			(at 70.109 324.489 0)
			(layer "B.Fab")
			(hide yes)
			(effects
				(font
					(size 1 1)
					(thickness 0.15)
				)
				(justify mirror)
			)
		)
		(property "Manufacturer" "Murata"
			(at 70.109 324.489 0)
			(layer "B.Fab")
			(hide yes)
			(effects
				(font
					(size 1 1)
					(thickness 0.15)
				)
				(justify mirror)
			)
		)
		(property "Public" ""
			(at 70.109 324.489 0)
			(layer "B.Fab")
			(hide yes)
			(effects
				(font
					(size 1 1)
					(thickness 0.15)
				)
				(justify mirror)
			)
		)
		(property "Val" "100n"
			(at 70.109 324.489 0)
			(layer "B.Fab")
			(hide yes)
			(effects
				(font
					(size 1 1)
					(thickness 0.15)
				)
				(justify mirror)
			)
		)
		(property "Voltage" "50V"
			(at 70.109 324.489 0)
			(layer "B.Fab")
			(hide yes)
			(effects
				(font
					(size 1 1)
					(thickness 0.15)
				)
				(justify mirror)
			)
		)
		(sheetname "/FPGA Supply/")
		(sheetfile "fpga-supply.kicad_sch")
		(attr smd)
		(fp_rect
			(start -0.925 0.47)
			(end 0.925 -0.47)
			(stroke
				(width 0.05)
				(type default)
			)
			(fill no)
			(layer "B.CrtYd")
		)
		(fp_line
			(start -0.494 0.25)
			(end 0.504 0.25)
			(stroke
				(width 0.15)
				(type solid)
			)
			(layer "B.Fab")
		)
		(fp_line
			(start 0.504 0.25)
			(end 0.504 -0.248)
			(stroke
				(width 0.15)
				(type solid)
			)
			(layer "B.Fab")
		)
		(fp_line
			(start -0.494 -0.248)
			(end -0.494 0.25)
			(stroke
				(width 0.15)
				(type solid)
			)
			(layer "B.Fab")
		)
		(fp_line
			(start 0.504 -0.248)
			(end -0.494 -0.248)
			(stroke
				(width 0.15)
				(type solid)
			)
			(layer "B.Fab")
		)
		(fp_text user "Author: Antmicro"
			(at -0.939 -3.399 90)
			(layer "B.Fab")
			(effects
				(font
					(size 0.7 0.7)
					(thickness 0.15)
				)
				(justify left bottom mirror)
			)
		)
		(fp_text user "${REFERENCE}"
			(at -0.939 -4.599 90)
			(layer "B.Fab")
			(effects
				(font
					(size 0.7 0.7)
					(thickness 0.15)
				)
				(justify left bottom mirror)
			)
		)
		(fp_text user "License: Apache-2.0"
			(at -0.939 -5.799 90)
			(layer "B.Fab")
			(effects
				(font
					(size 0.7 0.7)
					(thickness 0.15)
				)
				(justify left bottom mirror)
			)
		)
		(pad "1" smd roundrect
			(at -0.48 0 270)
			(size 0.59 0.64)
			(layers "B.Cu" "B.Mask" "B.Paste")
			(roundrect_rratio 0.25)
			(net 417 "GND")
			(pintype "passive")
		)
		(pad "2" smd roundrect
			(at 0.48 0 270)
			(size 0.59 0.64)
			(layers "B.Cu" "B.Mask" "B.Paste")
			(roundrect_rratio 0.25)
			(net 50 "+3V3")
			(pintype "passive")
		)
	)
	(footprint "antmicro-footprints:C_0402_1005Metric"
		(layer "B.Cu")
		(at 205 145.9 -90)
		(descr "Capacitor SMD 0402")
		(tags "capacitor SMD 0402")
		(property "Reference" "C198"
			(at -1.85 -1.5 90)
			(layer "B.SilkS")
			(effects
				(font
					(size 0.7 0.7)
					(thickness 0.15)
				)
				(justify left bottom mirror)
			)
		)
		(property "Value" "C_100n_0402"
			(at -1.022927 -2.155213 90)
			(layer "B.Fab")
			(hide yes)
			(effects
				(font
					(size 0.7 0.7)
					(thickness 0.15)
				)
				(justify left bottom mirror)
			)
		)
		(property "Datasheet" "https://www.murata.com/products/productdetail?partno=GRM155R61H104KE14%23"
			(at 0 0 270)
			(layer "F.Fab")
			(hide yes)
			(effects
				(font
					(size 1.27 1.27)
					(thickness 0.15)
				)
			)
		)
		(property "Description" "SMD Multilayer Ceramic Capacitor, 0.1 µF, 50 V, 0402 [1005 Metric], ± 10%, X5R, GRM Series"
			(at 0 0 270)
			(layer "F.Fab")
			(hide yes)
			(effects
				(font
					(size 1.27 1.27)
					(thickness 0.15)
				)
			)
		)
		(property "Author" "Antmicro"
			(at 59.1 350.9 0)
			(layer "B.Fab")
			(hide yes)
			(effects
				(font
					(size 1 1)
					(thickness 0.15)
				)
				(justify mirror)
			)
		)
		(property "Dielectric" "X5R"
			(at 59.1 350.9 0)
			(layer "B.Fab")
			(hide yes)
			(effects
				(font
					(size 1 1)
					(thickness 0.15)
				)
				(justify mirror)
			)
		)
		(property "License" "Apache-2.0"
			(at 59.1 350.9 0)
			(layer "B.Fab")
			(hide yes)
			(effects
				(font
					(size 1 1)
					(thickness 0.15)
				)
				(justify mirror)
			)
		)
		(property "MPN" "GRM155R61H104KE14D"
			(at 59.1 350.9 0)
			(layer "B.Fab")
			(hide yes)
			(effects
				(font
					(size 1 1)
					(thickness 0.15)
				)
				(justify mirror)
			)
		)
		(property "Manufacturer" "Murata"
			(at 59.1 350.9 0)
			(layer "B.Fab")
			(hide yes)
			(effects
				(font
					(size 1 1)
					(thickness 0.15)
				)
				(justify mirror)
			)
		)
		(property "Public" ""
			(at 59.1 350.9 0)
			(layer "B.Fab")
			(hide yes)
			(effects
				(font
					(size 1 1)
					(thickness 0.15)
				)
				(justify mirror)
			)
		)
		(property "Val" "100n"
			(at 59.1 350.9 0)
			(layer "B.Fab")
			(hide yes)
			(effects
				(font
					(size 1 1)
					(thickness 0.15)
				)
				(justify mirror)
			)
		)
		(property "Voltage" "50V"
			(at 59.1 350.9 0)
			(layer "B.Fab")
			(hide yes)
			(effects
				(font
					(size 1 1)
					(thickness 0.15)
				)
				(justify mirror)
			)
		)
		(sheetname "/MIPI CrossLink/")
		(sheetfile "crosslink.kicad_sch")
		(attr smd)
		(fp_rect
			(start -0.925 0.47)
			(end 0.925 -0.47)
			(stroke
				(width 0.05)
				(type default)
			)
			(fill no)
			(layer "B.CrtYd")
		)
		(fp_line
			(start -0.494 0.25)
			(end 0.504 0.25)
			(stroke
				(width 0.15)
				(type solid)
			)
			(layer "B.Fab")
		)
		(fp_line
			(start 0.504 0.25)
			(end 0.504 -0.248)
			(stroke
				(width 0.15)
				(type solid)
			)
			(layer "B.Fab")
		)
		(fp_line
			(start -0.494 -0.248)
			(end -0.494 0.25)
			(stroke
				(width 0.15)
				(type solid)
			)
			(layer "B.Fab")
		)
		(fp_line
			(start 0.504 -0.248)
			(end -0.494 -0.248)
			(stroke
				(width 0.15)
				(type solid)
			)
			(layer "B.Fab")
		)
		(fp_text user "Author: Antmicro"
			(at -0.939 -3.399 90)
			(layer "B.Fab")
			(effects
				(font
					(size 0.7 0.7)
					(thickness 0.15)
				)
				(justify left bottom mirror)
			)
		)
		(fp_text user "License: Apache-2.0"
			(at -0.939 -5.799 90)
			(layer "B.Fab")
			(effects
				(font
					(size 0.7 0.7)
					(thickness 0.15)
				)
				(justify left bottom mirror)
			)
		)
		(fp_text user "${REFERENCE}"
			(at -0.939 -4.599 90)
			(layer "B.Fab")
			(effects
				(font
					(size 0.7 0.7)
					(thickness 0.15)
				)
				(justify left bottom mirror)
			)
		)
		(pad "1" smd roundrect
			(at -0.48 0 270)
			(size 0.59 0.64)
			(layers "B.Cu" "B.Mask" "B.Paste")
			(roundrect_rratio 0.25)
			(net 417 "GND")
			(pintype "passive")
		)
		(pad "2" smd roundrect
			(at 0.48 0 270)
			(size 0.59 0.64)
			(layers "B.Cu" "B.Mask" "B.Paste")
			(roundrect_rratio 0.25)
			(net 183 "/MIPI CrossLink/CL_VCCIO0")
			(pintype "passive")
		)
	)
	(footprint "antmicro-footprints:C_0402_1005Metric"
		(layer "B.Cu")
		(at 215.361 123.254 -90)
		(descr "Capacitor SMD 0402")
		(tags "capacitor SMD 0402")
		(property "Reference" "C191"
			(at 1.886 -0.659 90)
			(layer "B.SilkS")
			(effects
				(font
					(size 0.7 0.7)
					(thickness 0.15)
				)
				(justify left bottom mirror)
			)
		)
		(property "Value" "C_100n_0402"
			(at -1.022927 -2.155213 90)
			(layer "B.Fab")
			(hide yes)
			(effects
				(font
					(size 0.7 0.7)
					(thickness 0.15)
				)
				(justify left bottom mirror)
			)
		)
		(property "Datasheet" "https://www.murata.com/products/productdetail?partno=GRM155R61H104KE14%23"
			(at 0 0 270)
			(layer "F.Fab")
			(hide yes)
			(effects
				(font
					(size 1.27 1.27)
					(thickness 0.15)
				)
			)
		)
		(property "Description" "SMD Multilayer Ceramic Capacitor, 0.1 µF, 50 V, 0402 [1005 Metric], ± 10%, X5R, GRM Series"
			(at 0 0 270)
			(layer "F.Fab")
			(hide yes)
			(effects
				(font
					(size 1.27 1.27)
					(thickness 0.15)
				)
			)
		)
		(property "Author" "Antmicro"
			(at 92.107 338.615 0)
			(layer "B.Fab")
			(hide yes)
			(effects
				(font
					(size 1 1)
					(thickness 0.15)
				)
				(justify mirror)
			)
		)
		(property "Dielectric" "X5R"
			(at 92.107 338.615 0)
			(layer "B.Fab")
			(hide yes)
			(effects
				(font
					(size 1 1)
					(thickness 0.15)
				)
				(justify mirror)
			)
		)
		(property "License" "Apache-2.0"
			(at 92.107 338.615 0)
			(layer "B.Fab")
			(hide yes)
			(effects
				(font
					(size 1 1)
					(thickness 0.15)
				)
				(justify mirror)
			)
		)
		(property "MPN" "GRM155R61H104KE14D"
			(at 92.107 338.615 0)
			(layer "B.Fab")
			(hide yes)
			(effects
				(font
					(size 1 1)
					(thickness 0.15)
				)
				(justify mirror)
			)
		)
		(property "Manufacturer" "Murata"
			(at 92.107 338.615 0)
			(layer "B.Fab")
			(hide yes)
			(effects
				(font
					(size 1 1)
					(thickness 0.15)
				)
				(justify mirror)
			)
		)
		(property "Public" ""
			(at 92.107 338.615 0)
			(layer "B.Fab")
			(hide yes)
			(effects
				(font
					(size 1 1)
					(thickness 0.15)
				)
				(justify mirror)
			)
		)
		(property "Val" "100n"
			(at 92.107 338.615 0)
			(layer "B.Fab")
			(hide yes)
			(effects
				(font
					(size 1 1)
					(thickness 0.15)
				)
				(justify mirror)
			)
		)
		(property "Voltage" "50V"
			(at 92.107 338.615 0)
			(layer "B.Fab")
			(hide yes)
			(effects
				(font
					(size 1 1)
					(thickness 0.15)
				)
				(justify mirror)
			)
		)
		(sheetname "/Ethernet/")
		(sheetfile "ethernet.kicad_sch")
		(attr smd)
		(fp_rect
			(start -0.925 0.47)
			(end 0.925 -0.47)
			(stroke
				(width 0.05)
				(type default)
			)
			(fill no)
			(layer "B.CrtYd")
		)
		(fp_line
			(start -0.494 0.25)
			(end 0.504 0.25)
			(stroke
				(width 0.15)
				(type solid)
			)
			(layer "B.Fab")
		)
		(fp_line
			(start 0.504 0.25)
			(end 0.504 -0.248)
			(stroke
				(width 0.15)
				(type solid)
			)
			(layer "B.Fab")
		)
		(fp_line
			(start -0.494 -0.248)
			(end -0.494 0.25)
			(stroke
				(width 0.15)
				(type solid)
			)
			(layer "B.Fab")
		)
		(fp_line
			(start 0.504 -0.248)
			(end -0.494 -0.248)
			(stroke
				(width 0.15)
				(type solid)
			)
			(layer "B.Fab")
		)
		(fp_text user "${REFERENCE}"
			(at -0.939 -4.599 90)
			(layer "B.Fab")
			(effects
				(font
					(size 0.7 0.7)
					(thickness 0.15)
				)
				(justify left bottom mirror)
			)
		)
		(fp_text user "License: Apache-2.0"
			(at -0.939 -5.799 90)
			(layer "B.Fab")
			(effects
				(font
					(size 0.7 0.7)
					(thickness 0.15)
				)
				(justify left bottom mirror)
			)
		)
		(fp_text user "Author: Antmicro"
			(at -0.939 -3.399 90)
			(layer "B.Fab")
			(effects
				(font
					(size 0.7 0.7)
					(thickness 0.15)
				)
				(justify left bottom mirror)
			)
		)
		(pad "1" smd roundrect
			(at -0.48 0 270)
			(size 0.59 0.64)
			(layers "B.Cu" "B.Mask" "B.Paste")
			(roundrect_rratio 0.25)
			(net 417 "GND")
			(pintype "passive")
		)
		(pad "2" smd roundrect
			(at 0.48 0 270)
			(size 0.59 0.64)
			(layers "B.Cu" "B.Mask" "B.Paste")
			(roundrect_rratio 0.25)
			(net 50 "+3V3")
			(pintype "passive")
		)
	)
	(footprint "antmicro-footprints:SOT-583"
		(layer "B.Cu")
		(at 219.3505 132.989 -90)
		(property "Reference" "U4"
			(at -1.089 -1.9495 180)
			(layer "B.SilkS")
			(effects
				(font
					(size 0.7 0.7)
					(thickness 0.15)
				)
				(justify left bottom mirror)
			)
		)
		(property "Value" "TPS2117DRLR"
			(at 0 -2.3 90)
			(layer "B.Fab")
			(hide yes)
			(effects
				(font
					(size 0.7 0.7)
					(thickness 0.15)
				)
				(justify left bottom mirror)
			)
		)
		(property "Datasheet" "https://www.ti.com/lit/ds/symlink/tps2117.pdf"
			(at 0 0 270)
			(layer "F.Fab")
			(hide yes)
			(effects
				(font
					(size 1.27 1.27)
					(thickness 0.15)
				)
			)
		)
		(property "Description" "TPS2117 1.6-V to 5.5-V, 4-A Low IQ Power Mux With Manual and Priority Switchover"
			(at 0 0 270)
			(layer "F.Fab")
			(hide yes)
			(effects
				(font
					(size 1.27 1.27)
					(thickness 0.15)
				)
			)
		)
		(property "Author" "Antmicro"
			(at 86.3615 352.3395 0)
			(layer "B.Fab")
			(hide yes)
			(effects
				(font
					(size 1 1)
					(thickness 0.15)
				)
				(justify mirror)
			)
		)
		(property "License" "Apache-2.0"
			(at 86.3615 352.3395 0)
			(layer "B.Fab")
			(hide yes)
			(effects
				(font
					(size 1 1)
					(thickness 0.15)
				)
				(justify mirror)
			)
		)
		(property "MPN" "TPS2117DRLR"
			(at 86.3615 352.3395 0)
			(layer "B.Fab")
			(hide yes)
			(effects
				(font
					(size 1 1)
					(thickness 0.15)
				)
				(justify mirror)
			)
		)
		(property "Manufacturer" "Texas Instruments"
			(at 86.3615 352.3395 0)
			(layer "B.Fab")
			(hide yes)
			(effects
				(font
					(size 1 1)
					(thickness 0.15)
				)
				(justify mirror)
			)
		)
		(property ki_fp_filters "DRL0008A-MFG")
		(sheetname "/Supply/")
		(sheetfile "supply.kicad_sch")
		(attr smd)
		(fp_line
			(start -0.65 1.15)
			(end 0.65 1.15)
			(stroke
				(width 0.15)
				(type solid)
			)
			(layer "B.SilkS")
		)
		(fp_line
			(start -0.651 -1.15)
			(end 0.651 -1.15)
			(stroke
				(width 0.15)
				(type solid)
			)
			(layer "B.SilkS")
		)
		(fp_circle
			(center -0.9 1.1)
			(end -0.85 1.05)
			(stroke
				(width 0.15)
				(type solid)
			)
			(fill yes)
			(layer "B.SilkS")
		)
		(fp_rect
			(start -1.15 1.3)
			(end 1.15 -1.3)
			(stroke
				(width 0.05)
				(type solid)
			)
			(fill no)
			(layer "B.CrtYd")
		)
		(fp_line
			(start -0.651 1.1005)
			(end 0.651 1.1005)
			(stroke
				(width 0.15)
				(type solid)
			)
			(layer "B.Fab")
		)
		(fp_line
			(start -0.651 -1.1005)
			(end -0.651 1.1005)
			(stroke
				(width 0.15)
				(type solid)
			)
			(layer "B.Fab")
		)
		(fp_line
			(start -0.651 -1.1005)
			(end 0.651 -1.1005)
			(stroke
				(width 0.15)
				(type solid)
			)
			(layer "B.Fab")
		)
		(fp_line
			(start 0.651 -1.1005)
			(end 0.651 1.1005)
			(stroke
				(width 0.15)
				(type solid)
			)
			(layer "B.Fab")
		)
		(fp_text user "License: Apache-2.0"
			(at -0.06 -6.025 90)
			(layer "B.Fab")
			(effects
				(font
					(size 0.7 0.7)
					(thickness 0.15)
				)
				(justify left bottom mirror)
			)
		)
		(fp_text user "Author: Antmicro"
			(at -0.06 -5.025 90)
			(layer "B.Fab")
			(effects
				(font
					(size 0.7 0.7)
					(thickness 0.15)
				)
				(justify left bottom mirror)
			)
		)
		(fp_text user "${REFERENCE}"
			(at -0.06 -4.025 90)
			(layer "B.Fab")
			(effects
				(font
					(size 0.7 0.7)
					(thickness 0.15)
				)
				(justify left bottom mirror)
			)
		)
		(pad "1" smd roundrect
			(at -0.739 0.7495 270)
			(size 0.670001 0.299999)
			(layers "B.Cu" "B.Mask" "B.Paste")
			(roundrect_rratio 0.25)
			(net 417 "GND")
			(pinfunction "GND")
			(pintype "power_in")
		)
		(pad "2" smd roundrect
			(at -0.739 0.2505 270)
			(size 0.670001 0.299999)
			(layers "B.Cu" "B.Mask" "B.Paste")
			(roundrect_rratio 0.25)
			(net 296 "Net-(R10-Pad2)")
			(pinfunction "VOUT")
			(pintype "power_out")
		)
		(pad "3" smd roundrect
			(at -0.739 -0.2495 270)
			(size 0.670001 0.299999)
			(layers "B.Cu" "B.Mask" "B.Paste")
			(roundrect_rratio 0.25)
			(net 50 "+3V3")
			(pinfunction "VIN1")
			(pintype "power_in")
		)
		(pad "4" smd roundrect
			(at -0.739 -0.7495 270)
			(size 0.670001 0.299999)
			(layers "B.Cu" "B.Mask" "B.Paste")
			(roundrect_rratio 0.25)
			(net 186 "/Supply/PR")
			(pinfunction "PR1")
			(pintype "input")
		)
		(pad "5" smd roundrect
			(at 0.74 -0.7495 270)
			(size 0.670001 0.299999)
			(layers "B.Cu" "B.Mask" "B.Paste")
			(roundrect_rratio 0.25)
			(net 50 "+3V3")
			(pinfunction "MODE")
			(pintype "input")
		)
		(pad "6" smd roundrect
			(at 0.74 -0.2495 270)
			(size 0.670001 0.299999)
			(layers "B.Cu" "B.Mask" "B.Paste")
			(roundrect_rratio 0.25)
			(net 48 "+1V8")
			(pinfunction "VIN2")
			(pintype "power_in")
		)
		(pad "7" smd roundrect
			(at 0.74 0.2505 270)
			(size 0.670001 0.299999)
			(layers "B.Cu" "B.Mask" "B.Paste")
			(roundrect_rratio 0.25)
			(net 296 "Net-(R10-Pad2)")
			(pinfunction "VOUT")
			(pintype "passive")
		)
		(pad "8" smd roundrect
			(at 0.74 0.7495 270)
			(size 0.670001 0.299999)
			(layers "B.Cu" "B.Mask" "B.Paste")
			(roundrect_rratio 0.25)
			(net 334 "VREF_FLAG")
			(pinfunction "ST")
			(pintype "output")
		)
	)
)
